# BASEBOARD_FAB2 (Tioga Pass) — schematic parts with pin connectivity, parts 2399–2399 of 4751; source: Cadence DE-HDL packaged netlist (pstxprt.dat, pstxnet.dat, pstchip.dat)

J9L1  SCONN288_H44441003  SCONN  pkg PIP  page 88
  1  \12v\(1)  = P12V_NVDIMM_KLM
  2  VSS(93)  GROUND  = GND
  3  DQ(4)  BI  = M_M_DQ<4>
  4  VSS(92)  GROUND  = GND
  5  DQ(0)  BI  = M_M_DQ<0>
  6  VSS(91)  GROUND  = GND
  7  DQS9P  BI  = M_M_DQS_DP<9>
  8  DQS9N  BI  = M_M_DQS_DN<9>
  9  VSS(90)  GROUND  = GND
  10  DQ(6)  BI  = M_M_DQ<6>
  11  VSS(89)  GROUND  = GND
  12  DQ(2)  BI  = M_M_DQ<2>
  13  VSS(88)  GROUND  = GND
  14  DQ(12)  BI  = M_M_DQ<12>
  15  VSS(87)  GROUND  = GND
  16  DQ(8)  BI  = M_M_DQ<8>
  17  VSS(86)  GROUND  = GND
  18  DQS10P  BI  = M_M_DQS_DP<10>
  19  DQS10N  BI  = M_M_DQS_DN<10>
  20  VSS(85)  GROUND  = GND
  21  DQ(14)  BI  = M_M_DQ<14>
  22  VSS(84)  GROUND  = GND
  23  DQ(10)  BI  = M_M_DQ<10>
  24  VSS(83)  GROUND  = GND
  25  DQ(20)  BI  = M_M_DQ<20>
  26  VSS(82)  GROUND  = GND
  27  DQ(16)  BI  = M_M_DQ<16>
  28  VSS(81)  GROUND  = GND
  29  DQS11P  BI  = M_M_DQS_DP<11>
  30  DQS11N  BI  = M_M_DQS_DN<11>
  31  VSS(80)  GROUND  = GND
  32  DQ(22)  BI  = M_M_DQ<22>
  33  VSS(79)  GROUND  = GND
  34  DQ(18)  BI  = M_M_DQ<18>
  35  VSS(78)  GROUND  = GND
  36  DQ(28)  BI  = M_M_DQ<28>
  37  VSS(77)  GROUND  = GND
  38  DQ(24)  BI  = M_M_DQ<24>
  39  VSS(76)  GROUND  = GND
  40  DQS12P  BI  = M_M_DQS_DP<12>
  41  DQS12N  BI  = M_M_DQS_DN<12>
  42  VSS(75)  GROUND  = GND
  43  DQ(30)  BI  = M_M_DQ<30>
  44  VSS(74)  GROUND  = GND
  45  DQ(26)  BI  = M_M_DQ<26>
  46  VSS(73)  GROUND  = GND
  47  CB(4)  BI  = M_M_ECC<4>
  48  VSS(72)  GROUND  = GND
  49  CB(0)  BI  = M_M_ECC<0>
  50  VSS(71)  GROUND  = GND
  51  DQS17P  BI  = M_M_DQS_DP<17>
  52  DQS17N  BI  = M_M_DQS_DN<17>
  53  VSS(70)  GROUND  = GND
  54  CB(6)  BI  = M_M_ECC<6>
  55  VSS(69)  GROUND  = GND
  56  CB(2)  BI  = M_M_ECC<2>
  57  VSS(68)  GROUND  = GND
  58  RESET_N  BI  = M_KLM_RST_N
  59  VDD(25)  POWER  = PVDDQ_KLM
  60  CKE(0)  BI  = M_M_CKE<2>
  61  VDD(24)  POWER  = PVDDQ_KLM
  62  ACT_N  BI  = M_M_ACT_N
  63  BG(0)  BI  = M_M_BG<0>
  64  VDD(23)  POWER  = PVDDQ_KLM
  65  A12  BI  = M_M_MA<12>
  66  A9  BI  = M_M_MA<9>
  67  VDD(22)  POWER  = PVDDQ_KLM
  68  A8  BI  = M_M_MA<8>
  69  A6  BI  = M_M_MA<6>
  70  VDD(21)  POWER  = PVDDQ_KLM
  71  A3  BI  = M_M_MA<3>
  72  A1  BI  = M_M_MA<1>
  73  VDD(20)  POWER  = PVDDQ_KLM
  74  CK0P  BI  = M_M_CLK_DP<2>
  75  CK0N  BI  = M_M_CLK_DN<2>
  76  VDD(19)  POWER  = PVDDQ_KLM
  77  VTT(1)  POWER  = PVTT_KLM
  78  EVENT_N  BI  = FM_DIMM_EVENT_COD_N
  79  A0  BI  = M_M_MA<0>
  80  VDD(18)  POWER  = PVDDQ_KLM
  81  BA(0)  BI  = M_M_BA<0>
  82  A16_RAS_N  BI  = M_M_MA<16>
  83  VDD(17)  POWER  = PVDDQ_KLM
  84  S0_N  BI  = M_M_CS_N<4>
  85  VDD(16)  POWER  = PVDDQ_KLM
  86  A15_CAS_N  BI  = M_M_MA<15>
  87  ODT(0)  BI  = M_M_ODT<2>
  88  VDD(15)  POWER  = PVDDQ_KLM
  89  S1_N  BI  = M_M_CS_N<5>
  90  VDD(14)  POWER  = PVDDQ_KLM
  91  ODT(1)  BI  = M_M_ODT<3>
  92  VDD(13)  POWER  = PVDDQ_KLM
  93  S2_N_C(0)  BI  = M_M_CS_N<6>
  94  VSS(67)  GROUND  = GND
  95  DQ(36)  BI  = M_M_DQ<36>
  96  VSS(66)  GROUND  = GND
  97  DQ(32)  BI  = M_M_DQ<32>
  98  VSS(65)  GROUND  = GND
  99  DQS13P  BI  = M_M_DQS_DP<13>
  100  DQS13N  BI  = M_M_DQS_DN<13>
  101  VSS(64)  GROUND  = GND
  102  DQ(38)  BI  = M_M_DQ<38>
  103  VSS(63)  GROUND  = GND
  104  DQ(34)  BI  = M_M_DQ<34>
  105  VSS(62)  GROUND  = GND
  106  DQ(44)  BI  = M_M_DQ<44>
  107  VSS(61)  GROUND  = GND
  108  DQ(40)  BI  = M_M_DQ<40>
  109  VSS(60)  GROUND  = GND
  110  DQS14P  BI  = M_M_DQS_DP<14>
  111  DQS14N  BI  = M_M_DQS_DN<14>
  112  VSS(59)  GROUND  = GND
  113  DQ(46)  BI  = M_M_DQ<46>
  114  VSS(58)  GROUND  = GND
  115  DQ(42)  BI  = M_M_DQ<42>
  116  VSS(57)  GROUND  = GND
  117  DQ(52)  BI  = M_M_DQ<52>
  118  VSS(56)  GROUND  = GND
  119  DQ(48)  BI  = M_M_DQ<48>
  120  VSS(55)  GROUND  = GND
  121  DQS15P  BI  = M_M_DQS_DP<15>
  122  DQS15N  BI  = M_M_DQS_DN<15>
  123  VSS(54)  GROUND  = GND
  124  DQ(54)  BI  = M_M_DQ<54>
  125  VSS(53)  GROUND  = GND
  126  DQ(50)  BI  = M_M_DQ<50>
  127  VSS(52)  GROUND  = GND
  128  DQ(60)  BI  = M_M_DQ<60>
  129  VSS(51)  GROUND  = GND
  130  DQ(56)  BI  = M_M_DQ<56>
  131  VSS(50)  GROUND  = GND
  132  DQS16P  BI  = M_M_DQS_DP<16>
  133  DQS16N  BI  = M_M_DQS_DN<16>
  134  VSS(49)  GROUND  = GND
  135  DQ(62)  BI  = M_M_DQ<62>
  136  VSS(48)  GROUND  = GND
  137  DQ(58)  BI  = M_M_DQ<58>
  138  VSS(47)  GROUND  = GND
  139  SA(0)  BI  = PVPP_KLM
  140  SA(1)  BI  = GND
  141  SCL  BI  = SMB_DDR_KLM_VPP_SCL
  142  VPP(4)  POWER  = PVPP_KLM
  143  VPP(3)  POWER  = PVPP_KLM
  144  RFU(2)  BI  = TP_CH_M_DIMM_M1_RFU_2
  145  \12v\(0)  = P12V_NVDIMM_KLM
  146  VREFCA  BI  = M_M_VREF
  147  VSS(46)  GROUND  = GND
  148  DQ(5)  BI  = M_M_DQ<5>
  149  VSS(45)  GROUND  = GND
  150  DQ(1)  BI  = M_M_DQ<1>
  151  VSS(44)  GROUND  = GND
  152  DQS0N  BI  = M_M_DQS_DN<0>
  153  DQS0P  BI  = M_M_DQS_DP<0>
  154  VSS(43)  GROUND  = GND
  155  DQ(7)  BI  = M_M_DQ<7>
  156  VSS(42)  GROUND  = GND
  157  DQ(3)  BI  = M_M_DQ<3>
  158  VSS(41)  GROUND  = GND
  159  DQ(13)  BI  = M_M_DQ<13>
  160  VSS(40)  GROUND  = GND
  161  DQ(9)  BI  = M_M_DQ<9>
  162  VSS(39)  GROUND  = GND
  163  DQS1N  BI  = M_M_DQS_DN<1>
  164  DQS1P  BI  = M_M_DQS_DP<1>
  165  VSS(38)  GROUND  = GND
  166  DQ(15)  BI  = M_M_DQ<15>
  167  VSS(37)  GROUND  = GND
  168  DQ(11)  BI  = M_M_DQ<11>
  169  VSS(36)  GROUND  = GND
  170  DQ(21)  BI  = M_M_DQ<21>
  171  VSS(35)  GROUND  = GND
  172  DQ(17)  BI  = M_M_DQ<17>
  173  VSS(34)  GROUND  = GND
  174  DQS2N  BI  = M_M_DQS_DN<2>
  175  DQS2P  BI  = M_M_DQS_DP<2>
  176  VSS(33)  GROUND  = GND
  177  DQ(23)  BI  = M_M_DQ<23>
  178  VSS(32)  GROUND  = GND
  179  DQ(19)  BI  = M_M_DQ<19>
  180  VSS(31)  GROUND  = GND
  181  DQ(29)  BI  = M_M_DQ<29>
  182  VSS(30)  GROUND  = GND
  183  DQ(25)  BI  = M_M_DQ<25>
  184  VSS(29)  GROUND  = GND
  185  DQS3N  BI  = M_M_DQS_DN<3>
  186  DQS3P  BI  = M_M_DQS_DP<3>
  187  VSS(28)  GROUND  = GND
  188  DQ(31)  BI  = M_M_DQ<31>
  189  VSS(27)  GROUND  = GND
  190  DQ(27)  BI  = M_M_DQ<27>
  191  VSS(26)  GROUND  = GND
  192  CB(5)  BI  = M_M_ECC<5>
  193  VSS(25)  GROUND  = GND
  194  CB(1)  BI  = M_M_ECC<1>
  195  VSS(24)  GROUND  = GND
  196  DQS8N  BI  = M_M_DQS_DN<8>
  197  DQS8P  BI  = M_M_DQS_DP<8>
  198  VSS(23)  GROUND  = GND
  199  CB(7)  BI  = M_M_ECC<7>
  200  VSS(22)  GROUND  = GND
  201  CB(3)  BI  = M_M_ECC<3>
  202  VSS(21)  GROUND  = GND
  203  CKE(1)  BI  = M_M_CKE<3>
  204  VDD(12)  POWER  = PVDDQ_KLM
  205  RFU(0)  BI  = TP_CH_M_DIMM_M1_RFU_0
  206  VDD(11)  POWER  = PVDDQ_KLM
  207  BG(1)  BI  = M_M_BG<1>
  208  ALERT_N  BI  = M_M_ALERT_N
  209  VDD(10)  POWER  = PVDDQ_KLM
  210  A11  BI  = M_M_MA<11>
  211  A7  BI  = M_M_MA<7>
  212  VDD(9)  POWER  = PVDDQ_KLM
  213  A5  BI  = M_M_MA<5>
  214  A4  BI  = M_M_MA<4>
  215  VDD(8)  POWER  = PVDDQ_KLM
  216  A2  BI  = M_M_MA<2>
  217  VDD(7)  POWER  = PVDDQ_KLM
  218  CK1P  BI  = M_M_CLK_DP<3>
  219  CK1N  BI  = M_M_CLK_DN<3>
  220  VDD(6)  POWER  = PVDDQ_KLM
  221  VTT(0)  POWER  = PVTT_KLM
  222  PAR  BI  = M_M_PAR
  223  VDD(5)  POWER  = PVDDQ_KLM
  224  BA(1)  BI  = M_M_BA<1>
  225  A10  BI  = M_M_MA<10>
  226  VDD(4)  POWER  = PVDDQ_KLM
  227  RFU(1)  BI  = TP_CH_M_DIMM_M1_RFU_1
  228  A14_WE_N  BI  = M_M_MA<14>
  229  VDD(3)  POWER  = PVDDQ_KLM
  230  SAVE_N_NC  BI  = FM_ADR_COMPLETE_KLM_N
  231  VDD(2)  POWER  = PVDDQ_KLM
  232  A13  BI  = M_M_MA<13>
  233  VDD(1)  POWER  = PVDDQ_KLM
  234  A17  BI  = M_M_MA<17>
  235  C(2)  BI  = M_M_C<2>
  236  VDD(0)  POWER  = PVDDQ_KLM
  237  S3_N_C(1)  BI  = M_M_CS_N<7>
  238  SA(2)  BI  = PVPP_KLM
  239  VSS(20)  GROUND  = GND
  240  DQ(37)  BI  = M_M_DQ<37>
  241  VSS(19)  GROUND  = GND
  242  DQ(33)  BI  = M_M_DQ<33>
  243  VSS(18)  GROUND  = GND
  244  DQS4N  BI  = M_M_DQS_DN<4>
  245  DQS4P  BI  = M_M_DQS_DP<4>
  246  VSS(17)  GROUND  = GND
  247  DQ(39)  BI  = M_M_DQ<39>
  248  VSS(16)  GROUND  = GND
  249  DQ(35)  BI  = M_M_DQ<35>
  250  VSS(15)  GROUND  = GND
  251  DQ(45)  BI  = M_M_DQ<45>
  252  VSS(14)  GROUND  = GND
  253  DQ(41)  BI  = M_M_DQ<41>
  254  VSS(13)  GROUND  = GND
  255  DQS5N  BI  = M_M_DQS_DN<5>
  256  DQS5P  BI  = M_M_DQS_DP<5>
  257  VSS(12)  GROUND  = GND
  258  DQ(47)  BI  = M_M_DQ<47>
  259  VSS(11)  GROUND  = GND
  260  DQ(43)  BI  = M_M_DQ<43>
  261  VSS(10)  GROUND  = GND
  262  DQ(53)  BI  = M_M_DQ<53>
  263  VSS(9)  GROUND  = GND
  264  DQ(49)  BI  = M_M_DQ<49>
  265  VSS(8)  GROUND  = GND
  266  DQS6N  BI  = M_M_DQS_DN<6>
  267  DQS6P  BI  = M_M_DQS_DP<6>
  268  VSS(7)  GROUND  = GND
  269  DQ(55)  BI  = M_M_DQ<55>
  270  VSS(6)  GROUND  = GND
  271  DQ(51)  BI  = M_M_DQ<51>
  272  VSS(5)  GROUND  = GND
  273  DQ(61)  BI  = M_M_DQ<61>
  274  VSS(4)  GROUND  = GND
  275  DQ(57)  BI  = M_M_DQ<57>
  276  VSS(3)  GROUND  = GND
  277  DQS7N  BI  = M_M_DQS_DN<7>
  278  DQS7P  BI  = M_M_DQS_DP<7>
  279  VSS(2)  GROUND  = GND
  280  DQ(63)  BI  = M_M_DQ<63>
  281  VSS(1)  GROUND  = GND
  282  DQ(59)  BI  = M_M_DQ<59>
  283  VSS(0)  GROUND  = GND
  284  VDDSPD  BI  = PVPP_KLM
  285  SDA  BI  = SMB_DDR_KLM_VPP_SDA
  286  VPP(1)  POWER  = PVPP_KLM
  287  VPP(0)  POWER  = PVPP_KLM
  288  VPP(2)  POWER  = PVPP_KLM
